(kicad_pcb
	(version 20240108)
	(generator "pcbnew")
	(generator_version "8.0")
	(general
		(thickness 1.6)
		(legacy_teardrops no)
	)
	(paper "A4")
	(title_block
		(title "Jetson Orin Baseboard OCuLink Expansion")
		(date "2025-03-18")
		(rev "1.1.0")
		(company "Antmicro Ltd")
		(comment 1 "www.antmicro.com")
		(comment 9 "footprints 14-18 of 119")
	)
	(layers
		(0 "F.Cu" signal)
		(1 "In1.Cu" signal)
		(2 "In2.Cu" signal)
		(31 "B.Cu" signal)
		(32 "B.Adhes" user "B.Adhesive")
		(33 "F.Adhes" user "F.Adhesive")
		(34 "B.Paste" user)
		(35 "F.Paste" user)
		(36 "B.SilkS" user "B.Silkscreen")
		(37 "F.SilkS" user "F.Silkscreen")
		(38 "B.Mask" user)
		(39 "F.Mask" user)
		(40 "Dwgs.User" user "User.Drawings")
		(41 "Cmts.User" user "User.Comments")
		(42 "Eco1.User" user "User.Eco1")
		(43 "Eco2.User" user "User.Eco2")
		(44 "Edge.Cuts" user)
		(45 "Margin" user)
		(46 "B.CrtYd" user "B.Courtyard")
		(47 "F.CrtYd" user "F.Courtyard")
		(48 "B.Fab" user)
		(49 "F.Fab" user)
	)
	(footprint "antmicro-footprints:C_0402_1005Metric"
		(layer "F.Cu")
		(at 118.59 137.64 -90)
		(descr "Capacitor SMD 0402")
		(tags "capacitor SMD 0402")
		(property "Reference" "C35"
			(at 0.86 0.34 90)
			(layer "F.SilkS")
			(effects
				(font
					(size 0.7 0.7)
					(thickness 0.15)
				)
				(justify right top)
			)
		)
		(property "Value" "C_220n_0402"
			(at -1.022927 2.155213 90)
			(layer "F.Fab")
			(effects
				(font
					(size 0.7 0.7)
					(thickness 0.15)
				)
				(justify right top)
			)
		)
		(property "Footprint" "antmicro-footprints:C_0402_1005Metric"
			(at 0 0 90)
			(layer "F.Fab")
			(hide yes)
			(effects
				(font
					(size 1.27 1.27)
					(thickness 0.15)
				)
			)
		)
		(property "Datasheet" "https://www.yageo.com/en/Chart/Download/pdf/CC0402KRX5R6BB224"
			(at 0 0 90)
			(layer "F.Fab")
			(hide yes)
			(effects
				(font
					(size 1.27 1.27)
					(thickness 0.15)
				)
			)
		)
		(property "Description" "SMD Multilayer Ceramic Capacitor, 0.22 µF, 10 V, 0402 [1005 Metric], ± 10%, X5R, CC Series"
			(at 0 0 90)
			(layer "F.Fab")
			(hide yes)
			(effects
				(font
					(size 1.27 1.27)
					(thickness 0.15)
				)
			)
		)
		(property "MPN" "CC0402KRX5R6BB224"
			(at 0 0 -90)
			(unlocked yes)
			(layer "F.Fab")
			(hide yes)
			(effects
				(font
					(size 1 1)
					(thickness 0.15)
				)
			)
		)
		(property "Manufacturer" "YAGEO"
			(at 0 0 -90)
			(unlocked yes)
			(layer "F.Fab")
			(hide yes)
			(effects
				(font
					(size 1 1)
					(thickness 0.15)
				)
			)
		)
		(property "License" "Apache-2.0"
			(at 0 0 -90)
			(unlocked yes)
			(layer "F.Fab")
			(hide yes)
			(effects
				(font
					(size 1 1)
					(thickness 0.15)
				)
			)
		)
		(property "Author" "Antmicro"
			(at 0 0 -90)
			(unlocked yes)
			(layer "F.Fab")
			(hide yes)
			(effects
				(font
					(size 1 1)
					(thickness 0.15)
				)
			)
		)
		(property "Val" "220n"
			(at 0 0 -90)
			(unlocked yes)
			(layer "F.Fab")
			(hide yes)
			(effects
				(font
					(size 1 1)
					(thickness 0.15)
				)
			)
		)
		(property "Voltage" ""
			(at 0 0 -90)
			(unlocked yes)
			(layer "F.Fab")
			(hide yes)
			(effects
				(font
					(size 1 1)
					(thickness 0.15)
				)
			)
		)
		(property "Dielectric" ""
			(at 0 0 -90)
			(unlocked yes)
			(layer "F.Fab")
			(hide yes)
			(effects
				(font
					(size 1 1)
					(thickness 0.15)
				)
			)
		)
		(property "Public" "False"
			(at 0 0 -90)
			(unlocked yes)
			(layer "F.Fab")
			(hide yes)
			(effects
				(font
					(size 1 1)
					(thickness 0.15)
				)
			)
		)
		(sheetname "Root")
		(sheetfile "jetson-orin-baseboard-oculink-expansion.kicad_sch")
		(attr smd)
		(fp_rect
			(start -0.925 -0.47)
			(end 0.925 0.47)
			(stroke
				(width 0.05)
				(type default)
			)
			(fill none)
			(layer "F.CrtYd")
		)
		(fp_line
			(start -0.494 0.248)
			(end -0.494 -0.25)
			(stroke
				(width 0.15)
				(type solid)
			)
			(layer "F.Fab")
		)
		(fp_line
			(start 0.504 0.248)
			(end -0.494 0.248)
			(stroke
				(width 0.15)
				(type solid)
			)
			(layer "F.Fab")
		)
		(fp_line
			(start -0.494 -0.25)
			(end 0.504 -0.25)
			(stroke
				(width 0.15)
				(type solid)
			)
			(layer "F.Fab")
		)
		(fp_line
			(start 0.504 -0.25)
			(end 0.504 0.248)
			(stroke
				(width 0.15)
				(type solid)
			)
			(layer "F.Fab")
		)
		(fp_text user "License: Apache-2.0"
			(at -0.939 5.799 90)
			(layer "F.Fab")
			(hide yes)
			(effects
				(font
					(size 0.7 0.7)
					(thickness 0.15)
				)
				(justify right top)
			)
		)
		(fp_text user "Author: Antmicro"
			(at -0.939 3.399 90)
			(layer "F.Fab")
			(hide yes)
			(effects
				(font
					(size 0.7 0.7)
					(thickness 0.15)
				)
				(justify right top)
			)
		)
		(fp_text user "${REFERENCE}"
			(at -0.939 4.599 90)
			(layer "F.Fab")
			(hide yes)
			(effects
				(font
					(size 0.7 0.7)
					(thickness 0.15)
				)
				(justify right top)
			)
		)
		(pad "1" smd roundrect
			(at -0.48 0 270)
			(size 0.59 0.64)
			(layers "F.Cu" "F.Paste" "F.Mask")
			(roundrect_rratio 0.25)
			(net 60 "/PCIE_{O}_C.TX1-")
			(pintype "passive")
		)
		(pad "2" smd roundrect
			(at 0.48 0 270)
			(size 0.59 0.64)
			(layers "F.Cu" "F.Paste" "F.Mask")
			(roundrect_rratio 0.25)
			(net 62 "/PCIE_{O}_TX1-")
			(pintype "passive")
		)
	)
	(footprint "antmicro-footprints:TP_SMD_0.75mm"
		(layer "F.Cu")
		(at 128.495 118.814751 180)
		(property "Reference" "TP12"
			(at -0.805 -0.485249 0)
			(layer "F.SilkS")
			(effects
				(font
					(size 0.7 0.7)
					(thickness 0.15)
				)
				(justify right top)
			)
		)
		(property "Value" "TP_0.75mm_SMD"
			(at 0 1.2 0)
			(layer "F.Fab")
			(effects
				(font
					(size 0.7 0.7)
					(thickness 0.15)
				)
				(justify right top)
			)
		)
		(property "Footprint" "antmicro-footprints:TP_SMD_0.75mm"
			(at 0 0 0)
			(layer "F.Fab")
			(hide yes)
			(effects
				(font
					(size 1.27 1.27)
					(thickness 0.15)
				)
			)
		)
		(property "Description" "SMT test point"
			(at 0 0 0)
			(layer "F.Fab")
			(hide yes)
			(effects
				(font
					(size 1.27 1.27)
					(thickness 0.15)
				)
			)
		)
		(property "MPN" ""
			(at 0 0 180)
			(unlocked yes)
			(layer "F.Fab")
			(hide yes)
			(effects
				(font
					(size 1 1)
					(thickness 0.15)
				)
			)
		)
		(property "Manufacturer" ""
			(at 0 0 180)
			(unlocked yes)
			(layer "F.Fab")
			(hide yes)
			(effects
				(font
					(size 1 1)
					(thickness 0.15)
				)
			)
		)
		(property "Author" "Antmicro"
			(at 0 0 180)
			(unlocked yes)
			(layer "F.Fab")
			(hide yes)
			(effects
				(font
					(size 1 1)
					(thickness 0.15)
				)
			)
		)
		(property "License" "Apache-2.0"
			(at 0 0 180)
			(unlocked yes)
			(layer "F.Fab")
			(hide yes)
			(effects
				(font
					(size 1 1)
					(thickness 0.15)
				)
			)
		)
		(property "Public" "False"
			(at 0 0 180)
			(unlocked yes)
			(layer "F.Fab")
			(hide yes)
			(effects
				(font
					(size 1 1)
					(thickness 0.15)
				)
			)
		)
		(sheetname "Root")
		(sheetfile "jetson-orin-baseboard-oculink-expansion.kicad_sch")
		(attr exclude_from_pos_files exclude_from_bom)
		(fp_circle
			(center 0 0)
			(end 0.475 0)
			(stroke
				(width 0.05)
				(type default)
			)
			(fill none)
			(layer "F.CrtYd")
		)
		(fp_text user "License: Apache-2.0"
			(at -0.4 5.101 0)
			(layer "F.Fab")
			(hide yes)
			(effects
				(font
					(size 0.7 0.7)
					(thickness 0.15)
				)
				(justify right top)
			)
		)
		(fp_text user "${REFERENCE}"
			(at -0.4 2.7 0)
			(layer "F.Fab")
			(hide yes)
			(effects
				(font
					(size 0.7 0.7)
					(thickness 0.15)
				)
				(justify right top)
			)
		)
		(fp_text user "Author: Antmicro"
			(at -0.4 3.901 0)
			(layer "F.Fab")
			(hide yes)
			(effects
				(font
					(size 0.7 0.7)
					(thickness 0.15)
				)
				(justify right top)
			)
		)
		(pad "1" smd circle
			(at 0 0 180)
			(size 0.75 0.75)
			(layers "F.Cu" "F.Mask")
			(net 110 "Net-(U2-~{I2C_{RESET}})")
			(pinfunction "1")
			(pintype "passive")
		)
	)
	(footprint "antmicro-footprints:C_0402_1005Metric"
		(layer "F.Cu")
		(at 111.1 146.306 90)
		(descr "Capacitor SMD 0402")
		(tags "capacitor SMD 0402")
		(property "Reference" "C3"
			(at 1.306 0.4 90)
			(layer "F.SilkS")
			(effects
				(font
					(size 0.7 0.7)
					(thickness 0.15)
				)
				(justify left bottom)
			)
		)
		(property "Value" "C_10u_0402"
			(at -1.022927 2.155213 90)
			(layer "F.Fab")
			(effects
				(font
					(size 0.7 0.7)
					(thickness 0.15)
				)
				(justify left bottom)
			)
		)
		(property "Footprint" "antmicro-footprints:C_0402_1005Metric"
			(at 0 0 90)
			(layer "F.Fab")
			(hide yes)
			(effects
				(font
					(size 1.27 1.27)
					(thickness 0.15)
				)
			)
		)
		(property "Datasheet" "https://www.yageo.com/en/Chart/Download/pdf/CC0402MRX5R5BB106"
			(at 0 0 90)
			(layer "F.Fab")
			(hide yes)
			(effects
				(font
					(size 1.27 1.27)
					(thickness 0.15)
				)
			)
		)
		(property "Description" "SMD Multilayer Ceramic Capacitor, 10 µF, 6.3 V, 0402 [1005 Metric], ± 20%, X5R, CC Series"
			(at 0 0 90)
			(layer "F.Fab")
			(hide yes)
			(effects
				(font
					(size 1.27 1.27)
					(thickness 0.15)
				)
			)
		)
		(property "MPN" "CC0402MRX5R5BB106"
			(at 0 0 90)
			(unlocked yes)
			(layer "F.Fab")
			(hide yes)
			(effects
				(font
					(size 1 1)
					(thickness 0.15)
				)
			)
		)
		(property "Manufacturer" "YAGEO"
			(at 0 0 90)
			(unlocked yes)
			(layer "F.Fab")
			(hide yes)
			(effects
				(font
					(size 1 1)
					(thickness 0.15)
				)
			)
		)
		(property "License" "Apache-2.0"
			(at 0 0 90)
			(unlocked yes)
			(layer "F.Fab")
			(hide yes)
			(effects
				(font
					(size 1 1)
					(thickness 0.15)
				)
			)
		)
		(property "Author" "Antmicro"
			(at 0 0 90)
			(unlocked yes)
			(layer "F.Fab")
			(hide yes)
			(effects
				(font
					(size 1 1)
					(thickness 0.15)
				)
			)
		)
		(property "Val" "10u"
			(at 0 0 90)
			(unlocked yes)
			(layer "F.Fab")
			(hide yes)
			(effects
				(font
					(size 1 1)
					(thickness 0.15)
				)
			)
		)
		(property "Voltage" ""
			(at 0 0 90)
			(unlocked yes)
			(layer "F.Fab")
			(hide yes)
			(effects
				(font
					(size 1 1)
					(thickness 0.15)
				)
			)
		)
		(property "Dielectric" ""
			(at 0 0 90)
			(unlocked yes)
			(layer "F.Fab")
			(hide yes)
			(effects
				(font
					(size 1 1)
					(thickness 0.15)
				)
			)
		)
		(sheetname "Root")
		(sheetfile "jetson-orin-baseboard-oculink-expansion.kicad_sch")
		(attr smd)
		(fp_rect
			(start -0.925 -0.47)
			(end 0.925 0.47)
			(stroke
				(width 0.05)
				(type default)
			)
			(fill none)
			(layer "F.CrtYd")
		)
		(fp_line
			(start 0.504 -0.25)
			(end 0.504 0.248)
			(stroke
				(width 0.15)
				(type solid)
			)
			(layer "F.Fab")
		)
		(fp_line
			(start -0.494 -0.25)
			(end 0.504 -0.25)
			(stroke
				(width 0.15)
				(type solid)
			)
			(layer "F.Fab")
		)
		(fp_line
			(start 0.504 0.248)
			(end -0.494 0.248)
			(stroke
				(width 0.15)
				(type solid)
			)
			(layer "F.Fab")
		)
		(fp_line
			(start -0.494 0.248)
			(end -0.494 -0.25)
			(stroke
				(width 0.15)
				(type solid)
			)
			(layer "F.Fab")
		)
		(fp_text user "${REFERENCE}"
			(at -0.939 4.599 90)
			(layer "F.Fab")
			(hide yes)
			(effects
				(font
					(size 0.7 0.7)
					(thickness 0.15)
				)
				(justify left bottom)
			)
		)
		(fp_text user "License: Apache-2.0"
			(at -0.939 5.799 90)
			(layer "F.Fab")
			(hide yes)
			(effects
				(font
					(size 0.7 0.7)
					(thickness 0.15)
				)
				(justify left bottom)
			)
		)
		(fp_text user "Author: Antmicro"
			(at -0.939 3.399 90)
			(layer "F.Fab")
			(hide yes)
			(effects
				(font
					(size 0.7 0.7)
					(thickness 0.15)
				)
				(justify left bottom)
			)
		)
		(pad "1" smd roundrect
			(at -0.48 0 90)
			(size 0.59 0.64)
			(layers "F.Cu" "F.Paste" "F.Mask")
			(roundrect_rratio 0.25)
			(net 51 "GND")
			(pintype "passive")
		)
		(pad "2" smd roundrect
			(at 0.48 0 90)
			(size 0.59 0.64)
			(layers "F.Cu" "F.Paste" "F.Mask")
			(roundrect_rratio 0.25)
			(net 132 "+3V3_OCU")
			(pintype "passive")
		)
	)
	(footprint "antmicro-footprints:R_0402_1005Metric"
		(layer "F.Cu")
		(at 131.46 117.17 180)
		(descr "Resistor SMD 0402")
		(tags "resistor SMD 0402")
		(property "Reference" "R36"
			(at -2.28 -0.55 180)
			(layer "F.SilkS")
			(effects
				(font
					(size 0.7 0.7)
					(thickness 0.15)
				)
				(justify right top)
			)
		)
		(property "Value" "R_0R_0402"
			(at -1.011843 1.772047 0)
			(layer "F.Fab")
			(effects
				(font
					(size 0.7 0.7)
					(thickness 0.15)
				)
				(justify right top)
			)
		)
		(property "Footprint" "antmicro-footprints:R_0402_1005Metric"
			(at 0 0 0)
			(layer "F.Fab")
			(hide yes)
			(effects
				(font
					(size 1.27 1.27)
					(thickness 0.15)
				)
			)
		)
		(property "Datasheet" "https://industrial.panasonic.com/cdbs/www-data/pdf/RDA0000/AOA0000C301.pdf"
			(at 0 0 0)
			(layer "F.Fab")
			(hide yes)
			(effects
				(font
					(size 1.27 1.27)
					(thickness 0.15)
				)
			)
		)
		(property "Description" "SMD Chip Resistor, Jumper, 0 ohm, 100 mW, 0402 [1005 Metric], Thick Film, General Purpose"
			(at 0 0 0)
			(layer "F.Fab")
			(hide yes)
			(effects
				(font
					(size 1.27 1.27)
					(thickness 0.15)
				)
			)
		)
		(property "MPN" "ERJ2GE0R00X"
			(at 0 0 180)
			(unlocked yes)
			(layer "F.Fab")
			(hide yes)
			(effects
				(font
					(size 1 1)
					(thickness 0.15)
				)
			)
		)
		(property "Manufacturer" "Panasonic"
			(at 0 0 180)
			(unlocked yes)
			(layer "F.Fab")
			(hide yes)
			(effects
				(font
					(size 1 1)
					(thickness 0.15)
				)
			)
		)
		(property "License" "Apache-2.0"
			(at 0 0 180)
			(unlocked yes)
			(layer "F.Fab")
			(hide yes)
			(effects
				(font
					(size 1 1)
					(thickness 0.15)
				)
			)
		)
		(property "Author" "Antmicro"
			(at 0 0 180)
			(unlocked yes)
			(layer "F.Fab")
			(hide yes)
			(effects
				(font
					(size 1 1)
					(thickness 0.15)
				)
			)
		)
		(property "Val" "0R"
			(at 0 0 180)
			(unlocked yes)
			(layer "F.Fab")
			(hide yes)
			(effects
				(font
					(size 1 1)
					(thickness 0.15)
				)
			)
		)
		(property "Tolerance" ""
			(at 0 0 180)
			(unlocked yes)
			(layer "F.Fab")
			(hide yes)
			(effects
				(font
					(size 1 1)
					(thickness 0.15)
				)
			)
		)
		(property "Current" "1A"
			(at 0 0 180)
			(unlocked yes)
			(layer "F.Fab")
			(hide yes)
			(effects
				(font
					(size 1 1)
					(thickness 0.15)
				)
			)
		)
		(property "Public" "False"
			(at 0 0 180)
			(unlocked yes)
			(layer "F.Fab")
			(hide yes)
			(effects
				(font
					(size 1 1)
					(thickness 0.15)
				)
			)
		)
		(sheetname "Root")
		(sheetfile "jetson-orin-baseboard-oculink-expansion.kicad_sch")
		(attr smd dnp)
		(fp_rect
			(start -0.925 -0.47)
			(end 0.925 0.47)
			(stroke
				(width 0.05)
				(type default)
			)
			(fill none)
			(layer "F.CrtYd")
		)
		(fp_rect
			(start -0.5 -0.25)
			(end 0.5 0.25)
			(stroke
				(width 0.15)
				(type solid)
			)
			(fill none)
			(layer "F.Fab")
		)
		(fp_text user "${REFERENCE}"
			(at -0.95 3.168 0)
			(layer "F.Fab")
			(hide yes)
			(effects
				(font
					(size 0.7 0.7)
					(thickness 0.15)
				)
				(justify right top)
			)
		)
		(fp_text user "License: Apache-2.0"
			(at -0.95 5.169 0)
			(layer "F.Fab")
			(hide yes)
			(effects
				(font
					(size 0.7 0.7)
					(thickness 0.15)
				)
				(justify right top)
			)
		)
		(fp_text user "Author: Antmicro"
			(at -0.95 4.169 0)
			(layer "F.Fab")
			(hide yes)
			(effects
				(font
					(size 0.7 0.7)
					(thickness 0.15)
				)
				(justify right top)
			)
		)
		(pad "1" smd roundrect
			(at -0.48 0 180)
			(size 0.59 0.64)
			(layers "F.Cu" "F.Paste" "F.Mask")
			(roundrect_rratio 0.25)
			(net 61 "/I2C_SDA")
			(pintype "passive")
		)
		(pad "2" smd roundrect
			(at 0.48 0 180)
			(size 0.59 0.64)
			(layers "F.Cu" "F.Paste" "F.Mask")
			(roundrect_rratio 0.25)
			(net 95 "Net-(U2-SDA)")
			(pintype "passive")
		)
	)
	(footprint "antmicro-footprints:R_0402_1005Metric"
		(layer "F.Cu")
		(at 141.1 140.5)
		(descr "Resistor SMD 0402")
		(tags "resistor SMD 0402")
		(property "Reference" "R3"
			(at -0.75 -0.35 0)
			(layer "F.SilkS")
			(effects
				(font
					(size 0.7 0.7)
					(thickness 0.15)
				)
				(justify left bottom)
			)
		)
		(property "Value" "R_10k_0402"
			(at -1.011843 1.772047 0)
			(layer "F.Fab")
			(effects
				(font
					(size 0.7 0.7)
					(thickness 0.15)
				)
				(justify left bottom)
			)
		)
		(property "Footprint" "antmicro-footprints:R_0402_1005Metric"
			(at 0 0 0)
			(layer "F.Fab")
			(hide yes)
			(effects
				(font
					(size 1.27 1.27)
					(thickness 0.15)
				)
			)
		)
		(property "Datasheet" "https://www.bourns.com/docs/product-datasheets/cr.pdf"
			(at 0 0 0)
			(layer "F.Fab")
			(hide yes)
			(effects
				(font
					(size 1.27 1.27)
					(thickness 0.15)
				)
			)
		)
		(property "Description" "SMD Chip Resistor, 10 kohm, ± 1%, 62.5 mW, 0402 [1005 Metric], Thick Film, General Purpose"
			(at 0 0 0)
			(layer "F.Fab")
			(hide yes)
			(effects
				(font
					(size 1.27 1.27)
					(thickness 0.15)
				)
			)
		)
		(property "MPN" "CR0402-FX-1002GLF"
			(at 0 0 0)
			(unlocked yes)
			(layer "F.Fab")
			(hide yes)
			(effects
				(font
					(size 1 1)
					(thickness 0.15)
				)
			)
		)
		(property "Manufacturer" "Bourns"
			(at 0 0 0)
			(unlocked yes)
			(layer "F.Fab")
			(hide yes)
			(effects
				(font
					(size 1 1)
					(thickness 0.15)
				)
			)
		)
		(property "License" "Apache-2.0"
			(at 0 0 0)
			(unlocked yes)
			(layer "F.Fab")
			(hide yes)
			(effects
				(font
					(size 1 1)
					(thickness 0.15)
				)
			)
		)
		(property "Author" "Antmicro"
			(at 0 0 0)
			(unlocked yes)
			(layer "F.Fab")
			(hide yes)
			(effects
				(font
					(size 1 1)
					(thickness 0.15)
				)
			)
		)
		(property "Val" "10k"
			(at 0 0 0)
			(unlocked yes)
			(layer "F.Fab")
			(hide yes)
			(effects
				(font
					(size 1 1)
					(thickness 0.15)
				)
			)
		)
		(property "Tolerance" "1%"
			(at 0 0 0)
			(unlocked yes)
			(layer "F.Fab")
			(hide yes)
			(effects
				(font
					(size 1 1)
					(thickness 0.15)
				)
			)
		)
		(sheetname "Root")
		(sheetfile "jetson-orin-baseboard-oculink-expansion.kicad_sch")
		(attr smd)
		(fp_rect
			(start -0.925 -0.47)
			(end 0.925 0.47)
			(stroke
				(width 0.05)
				(type default)
			)
			(fill none)
			(layer "F.CrtYd")
		)
		(fp_rect
			(start -0.5 -0.25)
			(end 0.5 0.25)
			(stroke
				(width 0.15)
				(type solid)
			)
			(fill none)
			(layer "F.Fab")
		)
		(fp_text user "License: Apache-2.0"
			(at -0.95 5.169 0)
			(layer "F.Fab")
			(hide yes)
			(effects
				(font
					(size 0.7 0.7)
					(thickness 0.15)
				)
				(justify left bottom)
			)
		)
		(fp_text user "Author: Antmicro"
			(at -0.95 4.169 0)
			(layer "F.Fab")
			(hide yes)
			(effects
				(font
					(size 0.7 0.7)
					(thickness 0.15)
				)
				(justify left bottom)
			)
		)
		(fp_text user "${REFERENCE}"
			(at -0.95 3.168 0)
			(layer "F.Fab")
			(hide yes)
			(effects
				(font
					(size 0.7 0.7)
					(thickness 0.15)
				)
				(justify left bottom)
			)
		)
		(pad "1" smd roundrect
			(at -0.48 0)
			(size 0.59 0.64)
			(layers "F.Cu" "F.Paste" "F.Mask")
			(roundrect_rratio 0.25)
			(net 51 "GND")
			(pintype "passive")
		)
		(pad "2" smd roundrect
			(at 0.48 0)
			(size 0.59 0.64)
			(layers "F.Cu" "F.Paste" "F.Mask")
			(roundrect_rratio 0.25)
			(net 70 "Net-(U1-~{THREE_STATE})")
			(pintype "passive")
		)
	)
)
